(kicad_pcb
	(version 20260206)
	(generator "pcbnew")
	(generator_version "10.0")
	(general
		(thickness 1.6)
		(legacy_teardrops no)
	)
	(paper "A4")
	(title_block
		(title "01162023_DA0F0TEBIF0_F0T_Expander_BD_F_brd_V02_OCP.brd")
		(comment 1 "Grand Teton / footprints 7247-7253 of 9728")
	)
	(layers
		(0 "F.Cu" signal "TOP")
		(4 "In1.Cu" signal "GND")
		(6 "In2.Cu" signal "VCC")
		(8 "In3.Cu" signal "VCC1")
		(10 "In4.Cu" signal "GND1")
		(12 "In5.Cu" signal "IN1")
		(14 "In6.Cu" signal "GND2")
		(16 "In7.Cu" signal "IN2")
		(18 "In8.Cu" signal "GND3")
		(20 "In9.Cu" signal "IN3")
		(22 "In10.Cu" signal "GND4")
		(24 "In11.Cu" signal "IN4")
		(26 "In12.Cu" signal "GND5")
		(28 "In13.Cu" signal "IN5")
		(30 "In14.Cu" signal "GND6")
		(32 "In15.Cu" signal "IN6")
		(34 "In16.Cu" signal "GND7")
		(2 "B.Cu" signal "BOTTOM")
		(9 "F.Adhes" user "F.Adhesive")
		(11 "B.Adhes" user "B.Adhesive")
		(13 "F.Paste" user "Package Geometry/Pastemask Top")
		(15 "B.Paste" user "Package Geometry/Pastemask Bottom")
		(5 "F.SilkS" user "Ref Des/Silkscreen Top")
		(7 "B.SilkS" user "Ref Des/Silkscreen Bottom")
		(1 "F.Mask" user "Board Geometry/Soldermask Top")
		(3 "B.Mask" user "Board Geometry/Soldermask Bottom")
		(17 "Dwgs.User" user "User.Drawings")
		(19 "Cmts.User" user "User.Comments")
		(21 "Eco1.User" user "User.Eco1")
		(23 "Eco2.User" user "User.Eco2")
		(25 "Edge.Cuts" user "Board Geometry/Outline")
		(27 "Margin" user)
		(31 "F.CrtYd" user "Package Geometry/Place Bound Top")
		(29 "B.CrtYd" user "Package Geometry/Place Bound Bottom")
		(35 "F.Fab" user "Ref Des/Assembly Top")
		(33 "B.Fab" user "Ref Des/Assembly Bottom")
	)
	(footprint ""
		(layer "B.Cu")
		(at 312.759344 20.568412)
		(property "Reference" "DE06F_3"
			(at 2.911856 3.054858 0)
			(unlocked yes)
			(layer "B.SilkS")
			(effects
				(font
					(size 0.7874 0.5842)
					(thickness 0.1524)
				)
				(justify left mirror)
			)
		)
		(property "Value" ""
			(at 0 0 0)
			(layer "B.Fab")
			(effects
				(font
					(size 1.27 1.27)
				)
				(justify mirror)
			)
		)
		(duplicate_pad_numbers_are_jumpers no)
		(fp_line
			(start -1.2192 -2.1082)
			(end -1.2192 2.1082)
			(stroke
				(width 0.1524)
				(type default)
			)
			(layer "B.SilkS")
		)
		(fp_line
			(start -1.2192 2.1082)
			(end 1.2192 2.1082)
			(stroke
				(width 0.1524)
				(type default)
			)
			(layer "B.SilkS")
		)
		(fp_line
			(start 1.2192 -2.1082)
			(end -1.2192 -2.1082)
			(stroke
				(width 0.1524)
				(type default)
			)
			(layer "B.SilkS")
		)
		(fp_line
			(start 1.2192 2.1082)
			(end 1.2192 -2.1082)
			(stroke
				(width 0.1524)
				(type default)
			)
			(layer "B.SilkS")
		)
		(pad "" np_thru_hole circle
			(at -3.4671 -1.27 270)
			(size 1.0414 1.0414)
			(drill 1.0414)
			(layers "*.Cu" "*.Mask")
			(clearance 0.381)
			(thermal_gap 0.381)
		)
		(pad "" np_thru_hole circle
			(at -3.4671 1.27 270)
			(size 1.0414 1.0414)
			(drill 1.0414)
			(layers "*.Cu" "*.Mask")
			(clearance 0.381)
			(thermal_gap 0.381)
		)
		(pad "" np_thru_hole circle
			(at 2.8829 -1.27 270)
			(size 1.0414 1.0414)
			(drill 1.0414)
			(layers "*.Cu" "*.Mask")
			(clearance 0.381)
			(thermal_gap 0.381)
		)
		(pad "" np_thru_hole circle
			(at 2.8829 1.27 270)
			(size 1.0414 1.0414)
			(drill 1.0414)
			(layers "*.Cu" "*.Mask")
			(clearance 0.381)
			(thermal_gap 0.381)
		)
		(pad "1" smd rect
			(at -0.8255 -0.249936 270)
			(size 0.3048 0.508)
			(layers "B.Cu" "B.Mask" "B.Paste")
			(net "85_5INCH_IN6_DP")
		)
		(pad "2" smd rect
			(at -0.8255 0.249936 270)
			(size 0.3048 0.508)
			(layers "B.Cu" "B.Mask" "B.Paste")
			(net "85_5INCH_IN6_DN")
		)
		(pad "3" smd circle
			(at 0 0 180)
			(size 0 0)
			(layers "B.Cu" "B.Mask" "B.Paste")
			(net "COUPON_GND2")
		)
		(zone
			(layers "F.Cu" "B.Cu" "In1.Cu" "In2.Cu" "In3.Cu" "In4.Cu" "In5.Cu" "In6.Cu"
				"In7.Cu" "In8.Cu" "In9.Cu" "In10.Cu" "In11.Cu" "In12.Cu" "In13.Cu" "In14.Cu"
				"In15.Cu" "In16.Cu"
			)
			(hatch none 0.5)
			(connect_pads
				(clearance 0)
			)
			(min_thickness 0.25)
			(keepout
				(tracks not_allowed)
				(vias allowed)
				(pads allowed)
				(copperpour not_allowed)
				(footprints allowed)
			)
			(placement
				(enabled no)
				(sheetname "")
			)
			(fill
				(thermal_gap 0.5)
				(thermal_bridge_width 0.5)
				(island_removal_mode 0)
			)
			(polygon
				(pts
					(arc
						(start 310.219344 19.298412)
						(mid 308.365144 19.298412)
						(end 310.219344 19.298412)
					)
				)
			)
		)
		(zone
			(layers "F.Cu" "B.Cu" "In1.Cu" "In2.Cu" "In3.Cu" "In4.Cu" "In5.Cu" "In6.Cu"
				"In7.Cu" "In8.Cu" "In9.Cu" "In10.Cu" "In11.Cu" "In12.Cu" "In13.Cu" "In14.Cu"
				"In15.Cu" "In16.Cu"
			)
			(hatch none 0.5)
			(connect_pads
				(clearance 0)
			)
			(min_thickness 0.25)
			(keepout
				(tracks not_allowed)
				(vias allowed)
				(pads allowed)
				(copperpour not_allowed)
				(footprints allowed)
			)
			(placement
				(enabled no)
				(sheetname "")
			)
			(fill
				(thermal_gap 0.5)
				(thermal_bridge_width 0.5)
				(island_removal_mode 0)
			)
			(polygon
				(pts
					(arc
						(start 310.219344 21.838412)
						(mid 308.365144 21.838412)
						(end 310.219344 21.838412)
					)
				)
			)
		)
		(zone
			(layers "F.Cu" "B.Cu" "In1.Cu" "In2.Cu" "In3.Cu" "In4.Cu" "In5.Cu" "In6.Cu"
				"In7.Cu" "In8.Cu" "In9.Cu" "In10.Cu" "In11.Cu" "In12.Cu" "In13.Cu" "In14.Cu"
				"In15.Cu" "In16.Cu"
			)
			(hatch none 0.5)
			(connect_pads
				(clearance 0)
			)
			(min_thickness 0.25)
			(keepout
				(tracks not_allowed)
				(vias allowed)
				(pads allowed)
				(copperpour not_allowed)
				(footprints allowed)
			)
			(placement
				(enabled no)
				(sheetname "")
			)
			(fill
				(thermal_gap 0.5)
				(thermal_bridge_width 0.5)
				(island_removal_mode 0)
			)
			(polygon
				(pts
					(arc
						(start 316.569344 19.298412)
						(mid 314.715144 19.298412)
						(end 316.569344 19.298412)
					)
				)
			)
		)
		(zone
			(layers "F.Cu" "B.Cu" "In1.Cu" "In2.Cu" "In3.Cu" "In4.Cu" "In5.Cu" "In6.Cu"
				"In7.Cu" "In8.Cu" "In9.Cu" "In10.Cu" "In11.Cu" "In12.Cu" "In13.Cu" "In14.Cu"
				"In15.Cu" "In16.Cu"
			)
			(hatch none 0.5)
			(connect_pads
				(clearance 0)
			)
			(min_thickness 0.25)
			(keepout
				(tracks not_allowed)
				(vias allowed)
				(pads allowed)
				(copperpour not_allowed)
				(footprints allowed)
			)
			(placement
				(enabled no)
				(sheetname "")
			)
			(fill
				(thermal_gap 0.5)
				(thermal_bridge_width 0.5)
				(island_removal_mode 0)
			)
			(polygon
				(pts
					(arc
						(start 316.569344 21.838412)
						(mid 314.715144 21.838412)
						(end 316.569344 21.838412)
					)
				)
			)
		)
		(zone
			(layer "B.Cu")
			(hatch none 0.5)
			(connect_pads
				(clearance 0)
			)
			(min_thickness 0.25)
			(keepout
				(tracks not_allowed)
				(vias allowed)
				(pads allowed)
				(copperpour not_allowed)
				(footprints allowed)
			)
			(placement
				(enabled no)
				(sheetname "")
			)
			(fill
				(thermal_gap 0.5)
				(thermal_bridge_width 0.5)
				(island_removal_mode 0)
			)
			(polygon
				(pts
					(xy 311.641744 20.019772) (xy 311.641744 20.115276) (xy 312.238644 20.115276) (xy 312.238644 20.521676)
					(xy 311.641744 20.521676) (xy 311.641744 20.615148) (xy 312.238644 20.615148) (xy 312.238644 21.021548)
					(xy 311.641744 21.021548) (xy 311.641744 21.117052) (xy 312.340244 21.117052) (xy 312.340244 20.019772)
				)
			)
		)
	)
	(footprint ""
		(layer "B.Cu")
		(at 413.174942 -293.99992 90)
		(property "Reference" "C1899"
			(at 0 0 90)
			(layer "B.SilkS")
			(hide yes)
			(effects
				(font
					(size 1.27 1.27)
				)
				(justify mirror)
			)
		)
		(property "Value" ""
			(at 0 0 90)
			(layer "B.Fab")
			(effects
				(font
					(size 1.27 1.27)
				)
				(justify mirror)
			)
		)
		(duplicate_pad_numbers_are_jumpers no)
		(fp_line
			(start 0.299974 -0.150114)
			(end -0.299974 -0.150114)
			(stroke
				(width 0.1)
				(type default)
			)
			(layer "B.Fab")
		)
		(fp_line
			(start -0.299974 -0.150114)
			(end -0.299974 0.150114)
			(stroke
				(width 0.1)
				(type default)
			)
			(layer "B.Fab")
		)
		(fp_line
			(start 0.299974 0.150114)
			(end 0.299974 -0.150114)
			(stroke
				(width 0.1)
				(type default)
			)
			(layer "B.Fab")
		)
		(fp_line
			(start -0.299974 0.150114)
			(end 0.299974 0.150114)
			(stroke
				(width 0.1)
				(type default)
			)
			(layer "B.Fab")
		)
		(pad "1" smd rect
			(at 0.2667 0 270)
			(size 0.3048 0.381)
			(layers "B.Cu" "B.Mask" "B.Paste")
			(net "P0V8_PEX3")
		)
		(pad "2" smd rect
			(at -0.2667 0 270)
			(size 0.3048 0.381)
			(layers "B.Cu" "B.Mask" "B.Paste")
			(net "GND")
		)
	)
	(footprint ""
		(layer "B.Cu")
		(at 396.07744 -300.7995 -90)
		(property "Reference" "C3544"
			(at 0 0 90)
			(layer "B.SilkS")
			(hide yes)
			(effects
				(font
					(size 1.27 1.27)
				)
				(justify mirror)
			)
		)
		(property "Value" ""
			(at 0 0 90)
			(layer "B.Fab")
			(effects
				(font
					(size 1.27 1.27)
				)
				(justify mirror)
			)
		)
		(duplicate_pad_numbers_are_jumpers no)
		(fp_line
			(start -0.299974 0.150114)
			(end 0.299974 0.150114)
			(stroke
				(width 0.1)
				(type default)
			)
			(layer "B.Fab")
		)
		(fp_line
			(start 0.299974 0.150114)
			(end 0.299974 -0.150114)
			(stroke
				(width 0.1)
				(type default)
			)
			(layer "B.Fab")
		)
		(fp_line
			(start -0.299974 -0.150114)
			(end -0.299974 0.150114)
			(stroke
				(width 0.1)
				(type default)
			)
			(layer "B.Fab")
		)
		(fp_line
			(start 0.299974 -0.150114)
			(end -0.299974 -0.150114)
			(stroke
				(width 0.1)
				(type default)
			)
			(layer "B.Fab")
		)
		(pad "1" smd rect
			(at 0.2667 0 90)
			(size 0.3048 0.381)
			(layers "B.Cu" "B.Mask" "B.Paste")
			(net "PCEPLL0_VDDA18_PEX3")
		)
		(pad "2" smd rect
			(at -0.2667 0 90)
			(size 0.3048 0.381)
			(layers "B.Cu" "B.Mask" "B.Paste")
			(net "GND")
		)
	)
	(footprint ""
		(layer "B.Cu")
		(at 193.641726 -103.104696 180)
		(property "Reference" "R169"
			(at 0 0 0)
			(layer "B.SilkS")
			(hide yes)
			(effects
				(font
					(size 1.27 1.27)
				)
				(justify mirror)
			)
		)
		(property "Value" ""
			(at 0 0 0)
			(layer "B.Fab")
			(effects
				(font
					(size 1.27 1.27)
				)
				(justify mirror)
			)
		)
		(duplicate_pad_numbers_are_jumpers no)
		(fp_line
			(start 0.7874 0.4064)
			(end 0.7874 -0.4064)
			(stroke
				(width 0.1524)
				(type default)
			)
			(layer "B.SilkS")
		)
		(fp_line
			(start 0.7874 -0.4064)
			(end -0.7874 -0.4064)
			(stroke
				(width 0.1524)
				(type default)
			)
			(layer "B.SilkS")
		)
		(fp_line
			(start -0.7874 0.4064)
			(end 0.7874 0.4064)
			(stroke
				(width 0.1524)
				(type default)
			)
			(layer "B.SilkS")
		)
		(fp_line
			(start -0.7874 -0.4064)
			(end -0.7874 0.4064)
			(stroke
				(width 0.1524)
				(type default)
			)
			(layer "B.SilkS")
		)
		(fp_line
			(start 0.67945 0.3048)
			(end 0.67945 -0.305054)
			(stroke
				(width 0.1)
				(type default)
			)
			(layer "B.Fab")
		)
		(fp_line
			(start 0.67945 -0.305054)
			(end 0.12065 -0.305054)
			(stroke
				(width 0.1)
				(type default)
			)
			(layer "B.Fab")
		)
		(fp_line
			(start 0.12065 0.3048)
			(end 0.67945 0.3048)
			(stroke
				(width 0.1)
				(type default)
			)
			(layer "B.Fab")
		)
		(fp_line
			(start 0.12065 0.2794)
			(end 0.12065 0.3048)
			(stroke
				(width 0.1)
				(type default)
			)
			(layer "B.Fab")
		)
		(fp_line
			(start 0.12065 -0.2794)
			(end -0.12065 -0.2794)
			(stroke
				(width 0.1)
				(type default)
			)
			(layer "B.Fab")
		)
		(fp_line
			(start 0.12065 -0.305054)
			(end 0.12065 -0.2794)
			(stroke
				(width 0.1)
				(type default)
			)
			(layer "B.Fab")
		)
		(fp_line
			(start -0.120396 0.3048)
			(end -0.120396 0.2794)
			(stroke
				(width 0.1)
				(type default)
			)
			(layer "B.Fab")
		)
		(fp_line
			(start -0.120396 0.2794)
			(end 0.12065 0.2794)
			(stroke
				(width 0.1)
				(type default)
			)
			(layer "B.Fab")
		)
		(fp_line
			(start -0.12065 -0.2794)
			(end -0.12065 -0.3048)
			(stroke
				(width 0.1)
				(type default)
			)
			(layer "B.Fab")
		)
		(fp_line
			(start -0.12065 -0.3048)
			(end -0.67945 -0.3048)
			(stroke
				(width 0.1)
				(type default)
			)
			(layer "B.Fab")
		)
		(fp_line
			(start -0.67945 0.3048)
			(end -0.120396 0.3048)
			(stroke
				(width 0.1)
				(type default)
			)
			(layer "B.Fab")
		)
		(fp_line
			(start -0.67945 -0.3048)
			(end -0.67945 0.3048)
			(stroke
				(width 0.1)
				(type default)
			)
			(layer "B.Fab")
		)
		(pad "1" smd circle
			(at 0.40005 0)
			(size 0 0)
			(layers "B.Cu" "B.Mask" "B.Paste")
			(net "NCSI_NIC3_RXD0")
		)
		(pad "2" smd circle
			(at -0.40005 0)
			(size 0 0)
			(layers "B.Cu" "B.Mask" "B.Paste")
			(net "GND")
		)
	)
	(footprint ""
		(layer "B.Cu")
		(at 175.749966 -299.699934 -90)
		(property "Reference" "C1472"
			(at 0 0 90)
			(layer "B.SilkS")
			(hide yes)
			(effects
				(font
					(size 1.27 1.27)
				)
				(justify mirror)
			)
		)
		(property "Value" ""
			(at 0 0 90)
			(layer "B.Fab")
			(effects
				(font
					(size 1.27 1.27)
				)
				(justify mirror)
			)
		)
		(duplicate_pad_numbers_are_jumpers no)
		(fp_line
			(start -0.299974 0.150114)
			(end 0.299974 0.150114)
			(stroke
				(width 0.1)
				(type default)
			)
			(layer "B.Fab")
		)
		(fp_line
			(start 0.299974 0.150114)
			(end 0.299974 -0.150114)
			(stroke
				(width 0.1)
				(type default)
			)
			(layer "B.Fab")
		)
		(fp_line
			(start -0.299974 -0.150114)
			(end -0.299974 0.150114)
			(stroke
				(width 0.1)
				(type default)
			)
			(layer "B.Fab")
		)
		(fp_line
			(start 0.299974 -0.150114)
			(end -0.299974 -0.150114)
			(stroke
				(width 0.1)
				(type default)
			)
			(layer "B.Fab")
		)
		(pad "1" smd rect
			(at 0.2667 0 90)
			(size 0.3048 0.381)
			(layers "B.Cu" "B.Mask" "B.Paste")
			(net "P0V8_SERDES_VDDA_PEX1")
		)
		(pad "2" smd rect
			(at -0.2667 0 90)
			(size 0.3048 0.381)
			(layers "B.Cu" "B.Mask" "B.Paste")
			(net "GND")
		)
	)
	(footprint ""
		(layer "B.Cu")
		(at 255.016254 -203.57465 180)
		(property "Reference" "R4298"
			(at 0 0 0)
			(layer "B.SilkS")
			(hide yes)
			(effects
				(font
					(size 1.27 1.27)
				)
				(justify mirror)
			)
		)
		(property "Value" ""
			(at 0 0 0)
			(layer "B.Fab")
			(effects
				(font
					(size 1.27 1.27)
				)
				(justify mirror)
			)
		)
		(duplicate_pad_numbers_are_jumpers no)
		(fp_line
			(start 0.7874 0.4064)
			(end 0.7874 -0.4064)
			(stroke
				(width 0.1524)
				(type default)
			)
			(layer "B.SilkS")
		)
		(fp_line
			(start 0.7874 -0.4064)
			(end -0.7874 -0.4064)
			(stroke
				(width 0.1524)
				(type default)
			)
			(layer "B.SilkS")
		)
		(fp_line
			(start -0.7874 0.4064)
			(end 0.7874 0.4064)
			(stroke
				(width 0.1524)
				(type default)
			)
			(layer "B.SilkS")
		)
		(fp_line
			(start -0.7874 -0.4064)
			(end -0.7874 0.4064)
			(stroke
				(width 0.1524)
				(type default)
			)
			(layer "B.SilkS")
		)
		(fp_line
			(start 0.67945 0.3048)
			(end 0.67945 -0.305054)
			(stroke
				(width 0.1)
				(type default)
			)
			(layer "B.Fab")
		)
		(fp_line
			(start 0.67945 -0.305054)
			(end 0.12065 -0.305054)
			(stroke
				(width 0.1)
				(type default)
			)
			(layer "B.Fab")
		)
		(fp_line
			(start 0.12065 0.3048)
			(end 0.67945 0.3048)
			(stroke
				(width 0.1)
				(type default)
			)
			(layer "B.Fab")
		)
		(fp_line
			(start 0.12065 0.2794)
			(end 0.12065 0.3048)
			(stroke
				(width 0.1)
				(type default)
			)
			(layer "B.Fab")
		)
		(fp_line
			(start 0.12065 -0.2794)
			(end -0.12065 -0.2794)
			(stroke
				(width 0.1)
				(type default)
			)
			(layer "B.Fab")
		)
		(fp_line
			(start 0.12065 -0.305054)
			(end 0.12065 -0.2794)
			(stroke
				(width 0.1)
				(type default)
			)
			(layer "B.Fab")
		)
		(fp_line
			(start -0.120396 0.3048)
			(end -0.120396 0.2794)
			(stroke
				(width 0.1)
				(type default)
			)
			(layer "B.Fab")
		)
		(fp_line
			(start -0.120396 0.2794)
			(end 0.12065 0.2794)
			(stroke
				(width 0.1)
				(type default)
			)
			(layer "B.Fab")
		)
		(fp_line
			(start -0.12065 -0.2794)
			(end -0.12065 -0.3048)
			(stroke
				(width 0.1)
				(type default)
			)
			(layer "B.Fab")
		)
		(fp_line
			(start -0.12065 -0.3048)
			(end -0.67945 -0.3048)
			(stroke
				(width 0.1)
				(type default)
			)
			(layer "B.Fab")
		)
		(fp_line
			(start -0.67945 0.3048)
			(end -0.120396 0.3048)
			(stroke
				(width 0.1)
				(type default)
			)
			(layer "B.Fab")
		)
		(fp_line
			(start -0.67945 -0.3048)
			(end -0.67945 0.3048)
			(stroke
				(width 0.1)
				(type default)
			)
			(layer "B.Fab")
		)
		(pad "1" smd circle
			(at 0.40005 0)
			(size 0 0)
			(layers "B.Cu" "B.Mask" "B.Paste")
			(net "JTAG_PLD_TDO")
		)
		(pad "2" smd circle
			(at -0.40005 0)
			(size 0 0)
			(layers "B.Cu" "B.Mask" "B.Paste")
			(net "JTAG_FPGA_TDO")
		)
	)
	(footprint ""
		(layer "B.Cu")
		(at 141.22273 -220.924374 90)
		(property "Reference" "R3467"
			(at 0 0 90)
			(layer "B.SilkS")
			(hide yes)
			(effects
				(font
					(size 1.27 1.27)
				)
				(justify mirror)
			)
		)
		(property "Value" ""
			(at 0 0 90)
			(layer "B.Fab")
			(effects
				(font
					(size 1.27 1.27)
				)
				(justify mirror)
			)
		)
		(duplicate_pad_numbers_are_jumpers no)
		(fp_line
			(start 0.7874 -0.4064)
			(end -0.7874 -0.4064)
			(stroke
				(width 0.1524)
				(type default)
			)
			(layer "B.SilkS")
		)
		(fp_line
			(start -0.7874 -0.4064)
			(end -0.7874 0.4064)
			(stroke
				(width 0.1524)
				(type default)
			)
			(layer "B.SilkS")
		)
		(fp_line
			(start 0.7874 0.4064)
			(end 0.7874 -0.4064)
			(stroke
				(width 0.1524)
				(type default)
			)
			(layer "B.SilkS")
		)
		(fp_line
			(start -0.7874 0.4064)
			(end 0.7874 0.4064)
			(stroke
				(width 0.1524)
				(type default)
			)
			(layer "B.SilkS")
		)
		(fp_line
			(start 0.67945 -0.305054)
			(end 0.12065 -0.305054)
			(stroke
				(width 0.1)
				(type default)
			)
			(layer "B.Fab")
		)
		(fp_line
			(start 0.12065 -0.305054)
			(end 0.12065 -0.2794)
			(stroke
				(width 0.1)
				(type default)
			)
			(layer "B.Fab")
		)
		(fp_line
			(start -0.12065 -0.3048)
			(end -0.67945 -0.3048)
			(stroke
				(width 0.1)
				(type default)
			)
			(layer "B.Fab")
		)
		(fp_line
			(start -0.67945 -0.3048)
			(end -0.67945 0.3048)
			(stroke
				(width 0.1)
				(type default)
			)
			(layer "B.Fab")
		)
		(fp_line
			(start 0.12065 -0.2794)
			(end -0.12065 -0.2794)
			(stroke
				(width 0.1)
				(type default)
			)
			(layer "B.Fab")
		)
		(fp_line
			(start -0.12065 -0.2794)
			(end -0.12065 -0.3048)
			(stroke
				(width 0.1)
				(type default)
			)
			(layer "B.Fab")
		)
		(fp_line
			(start 0.12065 0.2794)
			(end 0.12065 0.3048)
			(stroke
				(width 0.1)
				(type default)
			)
			(layer "B.Fab")
		)
		(fp_line
			(start -0.120396 0.2794)
			(end 0.12065 0.2794)
			(stroke
				(width 0.1)
				(type default)
			)
			(layer "B.Fab")
		)
		(fp_line
			(start 0.67945 0.3048)
			(end 0.67945 -0.305054)
			(stroke
				(width 0.1)
				(type default)
			)
			(layer "B.Fab")
		)
		(fp_line
			(start 0.12065 0.3048)
			(end 0.67945 0.3048)
			(stroke
				(width 0.1)
				(type default)
			)
			(layer "B.Fab")
		)
		(fp_line
			(start -0.120396 0.3048)
			(end -0.120396 0.2794)
			(stroke
				(width 0.1)
				(type default)
			)
			(layer "B.Fab")
		)
		(fp_line
			(start -0.67945 0.3048)
			(end -0.120396 0.3048)
			(stroke
				(width 0.1)
				(type default)
			)
			(layer "B.Fab")
		)
		(pad "1" smd circle
			(at 0.40005 0 270)
			(size 0 0)
			(layers "B.Cu" "B.Mask" "B.Paste")
			(net "P1V8_PEX")
		)
		(pad "2" smd circle
			(at -0.40005 0 270)
			(size 0 0)
			(layers "B.Cu" "B.Mask" "B.Paste")
			(net "SPI_PEX1_SDIO3_R1")
		)
	)
)
